# TIMECARD (Time Appliance Project (Time Card)) — schematic netlist excerpt (pin names and nets, part order shuffled) for the footprints in the layout excerpt that follows; sources: Cadence DE-HDL packaged netlist, KiCad conversion of R4006-B0001-02_R01.brd

R90  RESISTOR  100OHM 1%  pkg SMC_0402R_H016  page 21 : \1\ = R_MAC_PPS_IN0N ; \2\ = R_MAC_PPS_IN0P
C39  CAPACITOR  0.1UF 25V 10%  pkg SMC_0402R_H022  page 17 : \1\ = SG ; \2\ = XP3R3V_FPGA

(kicad_pcb
	(version 20260206)
	(generator "pcbnew")
	(generator_version "10.0")
	(general
		(thickness 1.6)
		(legacy_teardrops no)
	)
	(paper "A4")
	(title_block
		(title "timecard-production-celestica-r4006 — R4006-B0001-02_R01.brd")
		(comment 1 "Time Appliance Project (Time Card) / footprints 890-891 of 1113")
	)
	(layers
		(0 "F.Cu" signal "TOP")
		(4 "In1.Cu" signal "L02_GND1")
		(6 "In2.Cu" signal "L03_SIG1")
		(8 "In3.Cu" signal "L04_GND2")
		(10 "In4.Cu" signal "L05_VCC1")
		(12 "In5.Cu" signal "L06_VCC2")
		(14 "In6.Cu" signal "L07_GND3")
		(16 "In7.Cu" signal "L08_SIG2")
		(18 "In8.Cu" signal "L09_GND4")
		(2 "B.Cu" signal "BOTTOM")
		(9 "F.Adhes" user "F.Adhesive")
		(11 "B.Adhes" user "B.Adhesive")
		(13 "F.Paste" user "Package Geometry/Pastemask Top")
		(15 "B.Paste" user "Package Geometry/Pastemask Bottom")
		(5 "F.SilkS" user "Ref Des/Silkscreen Top")
		(7 "B.SilkS" user "Ref Des/Silkscreen Bottom")
		(1 "F.Mask" user "Board Geometry/Soldermask Top")
		(3 "B.Mask" user "Board Geometry/Soldermask Bottom")
		(17 "Dwgs.User" user "User.Drawings")
		(19 "Cmts.User" user "User.Comments")
		(21 "Eco1.User" user "User.Eco1")
		(23 "Eco2.User" user "User.Eco2")
		(25 "Edge.Cuts" user "Board Geometry/Outline")
		(27 "Margin" user)
		(31 "F.CrtYd" user "Package Geometry/Place Bound Top")
		(29 "B.CrtYd" user "Package Geometry/Place Bound Bottom")
		(35 "F.Fab" user "Ref Des/Assembly Top")
		(33 "B.Fab" user "Ref Des/Assembly Bottom")
	)
	(footprint ""
		(layer "B.Cu")
		(at 70.993 -47.2186 -90)
		(property "Reference" "R90"
			(at -0.0254 1.05537 270)
			(unlocked yes)
			(layer "B.SilkS")
			(effects
				(font
					(size 0.7874 0.5842)
					(thickness 0.1524)
				)
				(justify mirror)
			)
		)
		(property "Value" "VAL*"
			(at -0.02032 2.13233 270)
			(unlocked yes)
			(layer "B.Fab")
			(hide yes)
			(effects
				(font
					(size 0.7874 0.5842)
					(thickness 0.1524)
				)
				(justify mirror)
			)
		)
		(property "Device Type" "RESISTOR-G155-11000-01,100OHM,A"
			(at -0.008382 1.210564 270)
			(unlocked yes)
			(layer "B.Fab")
			(hide yes)
			(effects
				(font
					(size 0.7874 0.5842)
					(thickness 0.1524)
				)
				(justify mirror)
			)
		)
		(property "User Part Number" "PARTNUM*"
			(at -0.02032 4.024884 270)
			(unlocked yes)
			(layer "Cmts.User")
			(hide yes)
			(effects
				(font
					(size 0.7874 0.5842)
					(thickness 0.1524)
				)
				(justify mirror)
			)
		)
		(property "Tolerance" "TOL*"
			(at -0.044704 3.05435 270)
			(unlocked yes)
			(layer "Cmts.User")
			(hide yes)
			(effects
				(font
					(size 0.7874 0.5842)
					(thickness 0.1524)
				)
				(justify mirror)
			)
		)
		(duplicate_pad_numbers_are_jumpers no)
		(fp_line
			(start -1.143 0.5588)
			(end -1.143 -0.5588)
			(stroke
				(width 0.1)
				(type default)
			)
			(layer "B.SilkS")
		)
		(fp_line
			(start 1.143 0.5588)
			(end -1.143 0.5588)
			(stroke
				(width 0.1)
				(type default)
			)
			(layer "B.SilkS")
		)
		(fp_line
			(start -1.143 -0.5588)
			(end 1.143 -0.5588)
			(stroke
				(width 0.1)
				(type default)
			)
			(layer "B.SilkS")
		)
		(fp_line
			(start 1.143 -0.5588)
			(end 1.143 0.5588)
			(stroke
				(width 0.1)
				(type default)
			)
			(layer "B.SilkS")
		)
		(fp_rect
			(start 1.143 -0.5588)
			(end -1.143 0.5588)
			(stroke
				(width 0)
				(type default)
			)
			(fill no)
			(layer "B.CrtYd")
		)
		(fp_line
			(start -0.508 0.3048)
			(end -0.508 -0.3048)
			(stroke
				(width 0.1)
				(type default)
			)
			(layer "B.Fab")
		)
		(fp_line
			(start 0.508 0.3048)
			(end -0.508 0.3048)
			(stroke
				(width 0.1)
				(type default)
			)
			(layer "B.Fab")
		)
		(fp_line
			(start -0.508 -0.3048)
			(end 0.508 -0.3048)
			(stroke
				(width 0.1)
				(type default)
			)
			(layer "B.Fab")
		)
		(fp_line
			(start 0.508 -0.3048)
			(end 0.508 0.3048)
			(stroke
				(width 0.1)
				(type default)
			)
			(layer "B.Fab")
		)
		(pad "1" smd rect
			(at 0.5334 0 90)
			(size 0.7112 0.6096)
			(layers "B.Cu" "B.Mask" "B.Paste")
			(net "R_MAC_PPS_IN0N")
		)
		(pad "2" smd rect
			(at -0.5334 0 90)
			(size 0.7112 0.6096)
			(layers "B.Cu" "B.Mask" "B.Paste")
			(net "R_MAC_PPS_IN0P")
		)
		(zone
			(layer "B.Cu")
			(hatch none 0.5)
			(connect_pads
				(clearance 0)
			)
			(min_thickness 0.25)
			(keepout
				(tracks allowed)
				(vias not_allowed)
				(pads allowed)
				(copperpour not_allowed)
				(footprints allowed)
			)
			(placement
				(enabled no)
				(sheetname "")
			)
			(fill
				(thermal_gap 0.5)
				(thermal_bridge_width 0.5)
				(island_removal_mode 0)
			)
			(polygon
				(pts
					(xy 71.2978 -47.1424) (xy 71.2978 -47.2948) (xy 70.6882 -47.2948) (xy 70.6882 -47.1424)
				)
			)
		)
	)
	(footprint ""
		(layer "B.Cu")
		(at 5.588 -78.105 180)
		(property "Reference" "C39"
			(at 3.048 0.08763 0)
			(unlocked yes)
			(layer "B.SilkS")
			(effects
				(font
					(size 0.7874 0.5842)
					(thickness 0.1524)
				)
				(justify mirror)
			)
		)
		(property "Value" "VAL*"
			(at -0.0762 2.067306 180)
			(unlocked yes)
			(layer "B.Fab")
			(hide yes)
			(effects
				(font
					(size 0.7874 0.5842)
					(thickness 0.1524)
				)
				(justify mirror)
			)
		)
		(property "Tolerance" "TOL*"
			(at -0.0762 3.032506 180)
			(unlocked yes)
			(layer "Cmts.User")
			(hide yes)
			(effects
				(font
					(size 0.7874 0.5842)
					(thickness 0.1524)
				)
				(justify mirror)
			)
		)
		(property "User Part Number" "PARTNUM*"
			(at -0.1016 4.023106 180)
			(unlocked yes)
			(layer "Cmts.User")
			(hide yes)
			(effects
				(font
					(size 0.7874 0.5842)
					(thickness 0.1524)
				)
				(justify mirror)
			)
		)
		(property "Device Type" "CAPACITOR-G105-0B104-EK,0.1UF,A"
			(at -0.0508 1.127506 180)
			(unlocked yes)
			(layer "B.Fab")
			(hide yes)
			(effects
				(font
					(size 0.7874 0.5842)
					(thickness 0.1524)
				)
				(justify mirror)
			)
		)
		(duplicate_pad_numbers_are_jumpers no)
		(fp_line
			(start 1.143 0.5588)
			(end -1.143 0.5588)
			(stroke
				(width 0.1)
				(type default)
			)
			(layer "B.SilkS")
		)
		(fp_line
			(start 1.143 -0.5588)
			(end 1.143 0.5588)
			(stroke
				(width 0.1)
				(type default)
			)
			(layer "B.SilkS")
		)
		(fp_line
			(start -1.143 0.5588)
			(end -1.143 -0.5588)
			(stroke
				(width 0.1)
				(type default)
			)
			(layer "B.SilkS")
		)
		(fp_line
			(start -1.143 -0.5588)
			(end 1.143 -0.5588)
			(stroke
				(width 0.1)
				(type default)
			)
			(layer "B.SilkS")
		)
		(fp_rect
			(start -1.143 0.5588)
			(end 1.143 -0.5588)
			(stroke
				(width 0)
				(type default)
			)
			(fill no)
			(layer "B.CrtYd")
		)
		(fp_line
			(start 0.508 0.3048)
			(end -0.508 0.3048)
			(stroke
				(width 0.1)
				(type default)
			)
			(layer "B.Fab")
		)
		(fp_line
			(start 0.508 -0.3048)
			(end 0.508 0.3048)
			(stroke
				(width 0.1)
				(type default)
			)
			(layer "B.Fab")
		)
		(fp_line
			(start -0.508 0.3048)
			(end -0.508 -0.3048)
			(stroke
				(width 0.1)
				(type default)
			)
			(layer "B.Fab")
		)
		(fp_line
			(start -0.508 -0.3048)
			(end 0.508 -0.3048)
			(stroke
				(width 0.1)
				(type default)
			)
			(layer "B.Fab")
		)
		(pad "1" smd rect
			(at 0.5334 0)
			(size 0.7112 0.6096)
			(layers "B.Cu" "B.Mask" "B.Paste")
			(net "SG")
		)
		(pad "2" smd rect
			(at -0.5334 0)
			(size 0.7112 0.6096)
			(layers "B.Cu" "B.Mask" "B.Paste")
			(net "XP3R3V_FPGA")
		)
		(zone
			(layer "B.Cu")
			(hatch none 0.5)
			(connect_pads
				(clearance 0)
			)
			(min_thickness 0.25)
			(keepout
				(tracks allowed)
				(vias not_allowed)
				(pads allowed)
				(copperpour not_allowed)
				(footprints allowed)
			)
			(placement
				(enabled no)
				(sheetname "")
			)
			(fill
				(thermal_gap 0.5)
				(thermal_bridge_width 0.5)
				(island_removal_mode 0)
			)
			(polygon
				(pts
					(xy 5.6642 -78.4098) (xy 5.5118 -78.4098) (xy 5.5118 -77.8002) (xy 5.6642 -77.8002)
				)
			)
		)
	)
)
